(kicad_pcb
	(version 20260206)
	(generator "pcbnew")
	(generator_version "10.0")
	(general
		(thickness 1.6)
		(legacy_teardrops no)
	)
	(paper "A4")
	(title_block
		(title "12092022_DA0F0TFB6D0_F0T_FAN_BOARD_MP5048_D_brd_v02_OCP.brd")
		(comment 1 "Grand Teton / footprints 351-356 of 924")
	)
	(layers
		(0 "F.Cu" signal "TOP")
		(4 "In1.Cu" signal "GND")
		(6 "In2.Cu" signal "IN1")
		(8 "In3.Cu" signal "IN2")
		(10 "In4.Cu" signal "GND1")
		(2 "B.Cu" signal "BOTTOM")
		(9 "F.Adhes" user "F.Adhesive")
		(11 "B.Adhes" user "B.Adhesive")
		(13 "F.Paste" user "Package Geometry/Pastemask Top")
		(15 "B.Paste" user "Package Geometry/Pastemask Bottom")
		(5 "F.SilkS" user "Ref Des/Silkscreen Top")
		(7 "B.SilkS" user "Ref Des/Silkscreen Bottom")
		(1 "F.Mask" user "Board Geometry/Soldermask Top")
		(3 "B.Mask" user "Board Geometry/Soldermask Bottom")
		(17 "Dwgs.User" user "User.Drawings")
		(19 "Cmts.User" user "User.Comments")
		(21 "Eco1.User" user "User.Eco1")
		(23 "Eco2.User" user "User.Eco2")
		(25 "Edge.Cuts" user "Board Geometry/Outline")
		(27 "Margin" user)
		(31 "F.CrtYd" user "Package Geometry/Place Bound Top")
		(29 "B.CrtYd" user "Package Geometry/Place Bound Bottom")
		(35 "F.Fab" user "Ref Des/Assembly Top")
		(33 "B.Fab" user "Ref Des/Assembly Bottom")
	)
	(footprint ""
		(layer "F.Cu")
		(at 17.272 -160.02 -90)
		(property "Reference" "R5462"
			(at 0 0 270)
			(layer "F.SilkS")
			(hide yes)
			(effects
				(font
					(size 1.27 1.27)
				)
			)
		)
		(property "Value" ""
			(at 0 0 270)
			(layer "F.Fab")
			(effects
				(font
					(size 1.27 1.27)
				)
			)
		)
		(duplicate_pad_numbers_are_jumpers no)
		(fp_line
			(start -0.7874 0.4064)
			(end -0.7874 -0.4064)
			(stroke
				(width 0.1524)
				(type default)
			)
			(layer "F.SilkS")
		)
		(fp_line
			(start 0.7874 0.4064)
			(end -0.7874 0.4064)
			(stroke
				(width 0.1524)
				(type default)
			)
			(layer "F.SilkS")
		)
		(fp_line
			(start -0.7874 -0.4064)
			(end 0.7874 -0.4064)
			(stroke
				(width 0.1524)
				(type default)
			)
			(layer "F.SilkS")
		)
		(fp_line
			(start 0.7874 -0.4064)
			(end 0.7874 0.4064)
			(stroke
				(width 0.1524)
				(type default)
			)
			(layer "F.SilkS")
		)
		(fp_line
			(start -0.67945 0.3048)
			(end -0.67945 -0.305054)
			(stroke
				(width 0.1)
				(type default)
			)
			(layer "F.Fab")
		)
		(fp_line
			(start -0.12065 0.3048)
			(end -0.67945 0.3048)
			(stroke
				(width 0.1)
				(type default)
			)
			(layer "F.Fab")
		)
		(fp_line
			(start 0.120396 0.3048)
			(end 0.120396 0.2794)
			(stroke
				(width 0.1)
				(type default)
			)
			(layer "F.Fab")
		)
		(fp_line
			(start 0.67945 0.3048)
			(end 0.120396 0.3048)
			(stroke
				(width 0.1)
				(type default)
			)
			(layer "F.Fab")
		)
		(fp_line
			(start -0.12065 0.2794)
			(end -0.12065 0.3048)
			(stroke
				(width 0.1)
				(type default)
			)
			(layer "F.Fab")
		)
		(fp_line
			(start 0.120396 0.2794)
			(end -0.12065 0.2794)
			(stroke
				(width 0.1)
				(type default)
			)
			(layer "F.Fab")
		)
		(fp_line
			(start -0.12065 -0.2794)
			(end 0.12065 -0.2794)
			(stroke
				(width 0.1)
				(type default)
			)
			(layer "F.Fab")
		)
		(fp_line
			(start 0.12065 -0.2794)
			(end 0.12065 -0.3048)
			(stroke
				(width 0.1)
				(type default)
			)
			(layer "F.Fab")
		)
		(fp_line
			(start 0.12065 -0.3048)
			(end 0.67945 -0.3048)
			(stroke
				(width 0.1)
				(type default)
			)
			(layer "F.Fab")
		)
		(fp_line
			(start 0.67945 -0.3048)
			(end 0.67945 0.3048)
			(stroke
				(width 0.1)
				(type default)
			)
			(layer "F.Fab")
		)
		(fp_line
			(start -0.67945 -0.305054)
			(end -0.12065 -0.305054)
			(stroke
				(width 0.1)
				(type default)
			)
			(layer "F.Fab")
		)
		(fp_line
			(start -0.12065 -0.305054)
			(end -0.12065 -0.2794)
			(stroke
				(width 0.1)
				(type default)
			)
			(layer "F.Fab")
		)
		(pad "1" smd circle
			(at -0.40005 0 270)
			(size 0 0)
			(layers "F.Cu" "F.Mask" "F.Paste")
			(net "SMB_PDBV_FAN_SDA")
		)
		(pad "2" smd circle
			(at 0.40005 0 270)
			(size 0 0)
			(layers "F.Cu" "F.Mask" "F.Paste")
			(net "SMB_PDBV_FAN_R_U321_SDA")
		)
	)
	(footprint ""
		(layer "F.Cu")
		(at 33.147 -211.963)
		(property "Reference" "D273"
			(at -1.27 -1.595374 0)
			(unlocked yes)
			(layer "F.SilkS")
			(effects
				(font
					(size 0.7874 0.5842)
					(thickness 0.1524)
				)
				(justify left)
			)
		)
		(property "Value" ""
			(at 0 0 0)
			(layer "F.Fab")
			(effects
				(font
					(size 1.27 1.27)
				)
			)
		)
		(duplicate_pad_numbers_are_jumpers no)
		(fp_line
			(start -0.854964 -0.450088)
			(end -0.854964 0.450088)
			(stroke
				(width 0.1524)
				(type default)
			)
			(layer "F.SilkS")
		)
		(fp_line
			(start -0.854964 0.450088)
			(end 0.925068 0.450088)
			(stroke
				(width 0.1524)
				(type default)
			)
			(layer "F.SilkS")
		)
		(fp_line
			(start 0.845058 0.4064)
			(end 0.845058 -0.381)
			(stroke
				(width 0.1524)
				(type default)
			)
			(layer "F.SilkS")
		)
		(fp_line
			(start 0.870458 -0.2794)
			(end 0.845058 0.4064)
			(stroke
				(width 0.1524)
				(type default)
			)
			(layer "F.SilkS")
		)
		(fp_line
			(start 0.94488 -0.450088)
			(end -0.854964 -0.450088)
			(stroke
				(width 0.1524)
				(type default)
			)
			(layer "F.SilkS")
		)
		(fp_line
			(start 0.94488 0.450088)
			(end 0.94488 -0.450088)
			(stroke
				(width 0.1524)
				(type default)
			)
			(layer "F.SilkS")
		)
		(fp_line
			(start -0.54991 -0.350012)
			(end -0.54991 0.350012)
			(stroke
				(width 0.1)
				(type default)
			)
			(layer "F.Fab")
		)
		(fp_line
			(start -0.54991 0.350012)
			(end 0.54991 0.350012)
			(stroke
				(width 0.1)
				(type default)
			)
			(layer "F.Fab")
		)
		(fp_line
			(start 0.54991 -0.350012)
			(end -0.54991 -0.350012)
			(stroke
				(width 0.1)
				(type default)
			)
			(layer "F.Fab")
		)
		(fp_line
			(start 0.54991 0.350012)
			(end 0.54991 -0.350012)
			(stroke
				(width 0.1)
				(type default)
			)
			(layer "F.Fab")
		)
		(fp_text user "+"
			(at -0.635 0.251206 180)
			(unlocked yes)
			(layer "F.SilkS")
			(effects
				(font
					(size 1.905 1.4224)
					(thickness 0.1524)
				)
				(justify left)
			)
		)
		(fp_text user "-"
			(at 1.27 -0.637794 180)
			(unlocked yes)
			(layer "F.SilkS")
			(effects
				(font
					(size 1.905 1.4224)
					(thickness 0.1524)
				)
				(justify left)
			)
		)
		(fp_text user "+"
			(at -0.808228 0.239014 180)
			(unlocked yes)
			(layer "F.Fab")
			(effects
				(font
					(size 1.905 1.4224)
					(thickness 0.1524)
				)
				(justify left)
			)
		)
		(fp_text user "-"
			(at 2.48539 0.239014 180)
			(unlocked yes)
			(layer "F.Fab")
			(effects
				(font
					(size 1.905 1.4224)
					(thickness 0.1524)
				)
				(justify left)
			)
		)
		(pad "A" smd rect
			(at -0.424942 0)
			(size 0.5588 0.6096)
			(layers "F.Cu" "F.Mask" "F.Paste")
			(net "GND")
		)
		(pad "C" smd rect
			(at 0.424942 0 180)
			(size 0.5588 0.6096)
			(layers "F.Cu" "F.Mask" "F.Paste")
			(net "FAN_1_PWM_OL_R")
		)
	)
	(footprint ""
		(layer "F.Cu")
		(at 37.338 -300.609)
		(property "Reference" "D266"
			(at 1.651 -0.73533 0)
			(unlocked yes)
			(layer "F.SilkS")
			(effects
				(font
					(size 0.7874 0.5842)
					(thickness 0.1524)
				)
				(justify left)
			)
		)
		(property "Value" ""
			(at 0 0 0)
			(layer "F.Fab")
			(effects
				(font
					(size 1.27 1.27)
				)
			)
		)
		(duplicate_pad_numbers_are_jumpers no)
		(fp_line
			(start -0.854964 -0.450088)
			(end -0.854964 0.450088)
			(stroke
				(width 0.1524)
				(type default)
			)
			(layer "F.SilkS")
		)
		(fp_line
			(start -0.854964 0.450088)
			(end 0.925068 0.450088)
			(stroke
				(width 0.1524)
				(type default)
			)
			(layer "F.SilkS")
		)
		(fp_line
			(start 0.845058 0.4064)
			(end 0.845058 -0.381)
			(stroke
				(width 0.1524)
				(type default)
			)
			(layer "F.SilkS")
		)
		(fp_line
			(start 0.870458 -0.2794)
			(end 0.845058 0.4064)
			(stroke
				(width 0.1524)
				(type default)
			)
			(layer "F.SilkS")
		)
		(fp_line
			(start 0.94488 -0.450088)
			(end -0.854964 -0.450088)
			(stroke
				(width 0.1524)
				(type default)
			)
			(layer "F.SilkS")
		)
		(fp_line
			(start 0.94488 0.450088)
			(end 0.94488 -0.450088)
			(stroke
				(width 0.1524)
				(type default)
			)
			(layer "F.SilkS")
		)
		(fp_line
			(start -0.54991 -0.350012)
			(end -0.54991 0.350012)
			(stroke
				(width 0.1)
				(type default)
			)
			(layer "F.Fab")
		)
		(fp_line
			(start -0.54991 0.350012)
			(end 0.54991 0.350012)
			(stroke
				(width 0.1)
				(type default)
			)
			(layer "F.Fab")
		)
		(fp_line
			(start 0.54991 -0.350012)
			(end -0.54991 -0.350012)
			(stroke
				(width 0.1)
				(type default)
			)
			(layer "F.Fab")
		)
		(fp_line
			(start 0.54991 0.350012)
			(end 0.54991 -0.350012)
			(stroke
				(width 0.1)
				(type default)
			)
			(layer "F.Fab")
		)
		(fp_text user "+"
			(at -0.381 0.88265 180)
			(unlocked yes)
			(layer "F.SilkS")
			(effects
				(font
					(size 1.905 1.4224)
					(thickness 0.1524)
				)
				(justify left)
			)
		)
		(fp_text user "-"
			(at 2.159 0.22225 180)
			(unlocked yes)
			(layer "F.SilkS")
			(effects
				(font
					(size 1.905 1.4224)
					(thickness 0.1524)
				)
				(justify left)
			)
		)
		(fp_text user "+"
			(at -0.808228 0.239014 180)
			(unlocked yes)
			(layer "F.Fab")
			(effects
				(font
					(size 1.905 1.4224)
					(thickness 0.1524)
				)
				(justify left)
			)
		)
		(fp_text user "-"
			(at 2.48539 0.239014 180)
			(unlocked yes)
			(layer "F.Fab")
			(effects
				(font
					(size 1.905 1.4224)
					(thickness 0.1524)
				)
				(justify left)
			)
		)
		(pad "A" smd rect
			(at -0.424942 0)
			(size 0.5588 0.6096)
			(layers "F.Cu" "F.Mask" "F.Paste")
			(net "GND")
		)
		(pad "C" smd rect
			(at 0.424942 0 180)
			(size 0.5588 0.6096)
			(layers "F.Cu" "F.Mask" "F.Paste")
			(net "FAN_0_TACH_IL_D")
		)
	)
	(footprint ""
		(layer "F.Cu")
		(at 14.351 -292.608 180)
		(property "Reference" "R5243"
			(at 0 0 180)
			(layer "F.SilkS")
			(hide yes)
			(effects
				(font
					(size 1.27 1.27)
				)
			)
		)
		(property "Value" ""
			(at 0 0 180)
			(layer "F.Fab")
			(effects
				(font
					(size 1.27 1.27)
				)
			)
		)
		(duplicate_pad_numbers_are_jumpers no)
		(fp_line
			(start 0.7874 0.4064)
			(end -0.7874 0.4064)
			(stroke
				(width 0.1524)
				(type default)
			)
			(layer "F.SilkS")
		)
		(fp_line
			(start 0.7874 -0.4064)
			(end 0.7874 0.4064)
			(stroke
				(width 0.1524)
				(type default)
			)
			(layer "F.SilkS")
		)
		(fp_line
			(start -0.7874 0.4064)
			(end -0.7874 -0.4064)
			(stroke
				(width 0.1524)
				(type default)
			)
			(layer "F.SilkS")
		)
		(fp_line
			(start -0.7874 -0.4064)
			(end 0.7874 -0.4064)
			(stroke
				(width 0.1524)
				(type default)
			)
			(layer "F.SilkS")
		)
		(fp_line
			(start 0.67945 0.3048)
			(end 0.120396 0.3048)
			(stroke
				(width 0.1)
				(type default)
			)
			(layer "F.Fab")
		)
		(fp_line
			(start 0.67945 -0.3048)
			(end 0.67945 0.3048)
			(stroke
				(width 0.1)
				(type default)
			)
			(layer "F.Fab")
		)
		(fp_line
			(start 0.12065 -0.2794)
			(end 0.12065 -0.3048)
			(stroke
				(width 0.1)
				(type default)
			)
			(layer "F.Fab")
		)
		(fp_line
			(start 0.12065 -0.3048)
			(end 0.67945 -0.3048)
			(stroke
				(width 0.1)
				(type default)
			)
			(layer "F.Fab")
		)
		(fp_line
			(start 0.120396 0.3048)
			(end 0.120396 0.2794)
			(stroke
				(width 0.1)
				(type default)
			)
			(layer "F.Fab")
		)
		(fp_line
			(start 0.120396 0.2794)
			(end -0.12065 0.2794)
			(stroke
				(width 0.1)
				(type default)
			)
			(layer "F.Fab")
		)
		(fp_line
			(start -0.12065 0.3048)
			(end -0.67945 0.3048)
			(stroke
				(width 0.1)
				(type default)
			)
			(layer "F.Fab")
		)
		(fp_line
			(start -0.12065 0.2794)
			(end -0.12065 0.3048)
			(stroke
				(width 0.1)
				(type default)
			)
			(layer "F.Fab")
		)
		(fp_line
			(start -0.12065 -0.2794)
			(end 0.12065 -0.2794)
			(stroke
				(width 0.1)
				(type default)
			)
			(layer "F.Fab")
		)
		(fp_line
			(start -0.12065 -0.305054)
			(end -0.12065 -0.2794)
			(stroke
				(width 0.1)
				(type default)
			)
			(layer "F.Fab")
		)
		(fp_line
			(start -0.67945 0.3048)
			(end -0.67945 -0.305054)
			(stroke
				(width 0.1)
				(type default)
			)
			(layer "F.Fab")
		)
		(fp_line
			(start -0.67945 -0.305054)
			(end -0.12065 -0.305054)
			(stroke
				(width 0.1)
				(type default)
			)
			(layer "F.Fab")
		)
		(pad "1" smd circle
			(at -0.40005 0 180)
			(size 0 0)
			(layers "F.Cu" "F.Mask" "F.Paste")
			(net "SMB_FAN7_SCL")
		)
		(pad "2" smd circle
			(at 0.40005 0 180)
			(size 0 0)
			(layers "F.Cu" "F.Mask" "F.Paste")
			(net "SMB_FAN7_SCL_R")
		)
	)
	(footprint ""
		(layer "F.Cu")
		(at 37.338 -26.248868)
		(property "Reference" "R5242"
			(at 0 0 0)
			(layer "F.SilkS")
			(hide yes)
			(effects
				(font
					(size 1.27 1.27)
				)
			)
		)
		(property "Value" ""
			(at 0 0 0)
			(layer "F.Fab")
			(effects
				(font
					(size 1.27 1.27)
				)
			)
		)
		(duplicate_pad_numbers_are_jumpers no)
		(fp_line
			(start -0.7874 -0.4064)
			(end 0.7874 -0.4064)
			(stroke
				(width 0.1524)
				(type default)
			)
			(layer "F.SilkS")
		)
		(fp_line
			(start -0.7874 0.4064)
			(end -0.7874 -0.4064)
			(stroke
				(width 0.1524)
				(type default)
			)
			(layer "F.SilkS")
		)
		(fp_line
			(start 0.7874 -0.4064)
			(end 0.7874 0.4064)
			(stroke
				(width 0.1524)
				(type default)
			)
			(layer "F.SilkS")
		)
		(fp_line
			(start 0.7874 0.4064)
			(end -0.7874 0.4064)
			(stroke
				(width 0.1524)
				(type default)
			)
			(layer "F.SilkS")
		)
		(fp_line
			(start -0.67945 -0.305054)
			(end -0.12065 -0.305054)
			(stroke
				(width 0.1)
				(type default)
			)
			(layer "F.Fab")
		)
		(fp_line
			(start -0.67945 0.3048)
			(end -0.67945 -0.305054)
			(stroke
				(width 0.1)
				(type default)
			)
			(layer "F.Fab")
		)
		(fp_line
			(start -0.12065 -0.305054)
			(end -0.12065 -0.2794)
			(stroke
				(width 0.1)
				(type default)
			)
			(layer "F.Fab")
		)
		(fp_line
			(start -0.12065 -0.2794)
			(end 0.12065 -0.2794)
			(stroke
				(width 0.1)
				(type default)
			)
			(layer "F.Fab")
		)
		(fp_line
			(start -0.12065 0.2794)
			(end -0.12065 0.3048)
			(stroke
				(width 0.1)
				(type default)
			)
			(layer "F.Fab")
		)
		(fp_line
			(start -0.12065 0.3048)
			(end -0.67945 0.3048)
			(stroke
				(width 0.1)
				(type default)
			)
			(layer "F.Fab")
		)
		(fp_line
			(start 0.120396 0.2794)
			(end -0.12065 0.2794)
			(stroke
				(width 0.1)
				(type default)
			)
			(layer "F.Fab")
		)
		(fp_line
			(start 0.120396 0.3048)
			(end 0.120396 0.2794)
			(stroke
				(width 0.1)
				(type default)
			)
			(layer "F.Fab")
		)
		(fp_line
			(start 0.12065 -0.3048)
			(end 0.67945 -0.3048)
			(stroke
				(width 0.1)
				(type default)
			)
			(layer "F.Fab")
		)
		(fp_line
			(start 0.12065 -0.2794)
			(end 0.12065 -0.3048)
			(stroke
				(width 0.1)
				(type default)
			)
			(layer "F.Fab")
		)
		(fp_line
			(start 0.67945 -0.3048)
			(end 0.67945 0.3048)
			(stroke
				(width 0.1)
				(type default)
			)
			(layer "F.Fab")
		)
		(fp_line
			(start 0.67945 0.3048)
			(end 0.120396 0.3048)
			(stroke
				(width 0.1)
				(type default)
			)
			(layer "F.Fab")
		)
		(pad "1" smd circle
			(at -0.40005 0)
			(size 0 0)
			(layers "F.Cu" "F.Mask" "F.Paste")
			(net "SMB_FAN3_SCL")
		)
		(pad "2" smd circle
			(at 0.40005 0)
			(size 0 0)
			(layers "F.Cu" "F.Mask" "F.Paste")
			(net "SMB_FAN3_SCL_R")
		)
	)
	(footprint ""
		(layer "F.Cu")
		(at 26.035 -13.8938 -90)
		(property "Reference" "R4969"
			(at 0 0 270)
			(layer "F.SilkS")
			(hide yes)
			(effects
				(font
					(size 1.27 1.27)
				)
			)
		)
		(property "Value" ""
			(at 0 0 270)
			(layer "F.Fab")
			(effects
				(font
					(size 1.27 1.27)
				)
			)
		)
		(duplicate_pad_numbers_are_jumpers no)
		(fp_line
			(start -0.7874 0.4064)
			(end -0.7874 -0.4064)
			(stroke
				(width 0.1524)
				(type default)
			)
			(layer "F.SilkS")
		)
		(fp_line
			(start 0.7874 0.4064)
			(end -0.7874 0.4064)
			(stroke
				(width 0.1524)
				(type default)
			)
			(layer "F.SilkS")
		)
		(fp_line
			(start -0.7874 -0.4064)
			(end 0.7874 -0.4064)
			(stroke
				(width 0.1524)
				(type default)
			)
			(layer "F.SilkS")
		)
		(fp_line
			(start 0.7874 -0.4064)
			(end 0.7874 0.4064)
			(stroke
				(width 0.1524)
				(type default)
			)
			(layer "F.SilkS")
		)
		(fp_line
			(start -0.67945 0.3048)
			(end -0.67945 -0.305054)
			(stroke
				(width 0.1)
				(type default)
			)
			(layer "F.Fab")
		)
		(fp_line
			(start -0.12065 0.3048)
			(end -0.67945 0.3048)
			(stroke
				(width 0.1)
				(type default)
			)
			(layer "F.Fab")
		)
		(fp_line
			(start 0.120396 0.3048)
			(end 0.120396 0.2794)
			(stroke
				(width 0.1)
				(type default)
			)
			(layer "F.Fab")
		)
		(fp_line
			(start 0.67945 0.3048)
			(end 0.120396 0.3048)
			(stroke
				(width 0.1)
				(type default)
			)
			(layer "F.Fab")
		)
		(fp_line
			(start -0.12065 0.2794)
			(end -0.12065 0.3048)
			(stroke
				(width 0.1)
				(type default)
			)
			(layer "F.Fab")
		)
		(fp_line
			(start 0.120396 0.2794)
			(end -0.12065 0.2794)
			(stroke
				(width 0.1)
				(type default)
			)
			(layer "F.Fab")
		)
		(fp_line
			(start -0.12065 -0.2794)
			(end 0.12065 -0.2794)
			(stroke
				(width 0.1)
				(type default)
			)
			(layer "F.Fab")
		)
		(fp_line
			(start 0.12065 -0.2794)
			(end 0.12065 -0.3048)
			(stroke
				(width 0.1)
				(type default)
			)
			(layer "F.Fab")
		)
		(fp_line
			(start 0.12065 -0.3048)
			(end 0.67945 -0.3048)
			(stroke
				(width 0.1)
				(type default)
			)
			(layer "F.Fab")
		)
		(fp_line
			(start 0.67945 -0.3048)
			(end 0.67945 0.3048)
			(stroke
				(width 0.1)
				(type default)
			)
			(layer "F.Fab")
		)
		(fp_line
			(start -0.67945 -0.305054)
			(end -0.12065 -0.305054)
			(stroke
				(width 0.1)
				(type default)
			)
			(layer "F.Fab")
		)
		(fp_line
			(start -0.12065 -0.305054)
			(end -0.12065 -0.2794)
			(stroke
				(width 0.1)
				(type default)
			)
			(layer "F.Fab")
		)
		(pad "1" smd circle
			(at -0.40005 0 270)
			(size 0 0)
			(layers "F.Cu" "F.Mask" "F.Paste")
			(net "SMB_PDBV_FAN_SDA")
		)
		(pad "2" smd circle
			(at 0.40005 0 270)
			(size 0 0)
			(layers "F.Cu" "F.Mask" "F.Paste")
			(net "SMB_PDBV_FAN_R_SDA")
		)
	)
)
